(kicad_pcb
	(version 20260206)
	(generator "pcbnew")
	(generator_version "10.0")
	(general
		(thickness 1.6)
		(legacy_teardrops no)
	)
	(paper "A4")
	(title_block
		(title "Bryce Canyon_F.DPB_16315-1-OCP.brd")
		(comment 1 "Bryce Canyon / footprints 179-182 of 2223")
	)
	(layers
		(0 "F.Cu" signal "TOP")
		(4 "In1.Cu" signal "L2GND")
		(6 "In2.Cu" signal "L3")
		(8 "In3.Cu" signal "L4GND")
		(10 "In4.Cu" signal "L5")
		(12 "In5.Cu" signal "L6VCC")
		(14 "In6.Cu" signal "L7VCC")
		(16 "In7.Cu" signal "L8")
		(18 "In8.Cu" signal "L9GND")
		(20 "In9.Cu" signal "L10")
		(22 "In10.Cu" signal "L11GND")
		(2 "B.Cu" signal "BOTTOM")
		(9 "F.Adhes" user "F.Adhesive")
		(11 "B.Adhes" user "B.Adhesive")
		(13 "F.Paste" user "Package Geometry/Pastemask Top")
		(15 "B.Paste" user "Package Geometry/Pastemask Bottom")
		(5 "F.SilkS" user "Ref Des/Silkscreen Top")
		(7 "B.SilkS" user "Ref Des/Silkscreen Bottom")
		(1 "F.Mask" user "Board Geometry/Soldermask Top")
		(3 "B.Mask" user "Board Geometry/Soldermask Bottom")
		(17 "Dwgs.User" user "User.Drawings")
		(19 "Cmts.User" user "User.Comments")
		(21 "Eco1.User" user "User.Eco1")
		(23 "Eco2.User" user "User.Eco2")
		(25 "Edge.Cuts" user "Board Geometry/Outline")
		(27 "Margin" user)
		(31 "F.CrtYd" user "Package Geometry/Place Bound Top")
		(29 "B.CrtYd" user "Package Geometry/Place Bound Bottom")
		(35 "F.Fab" user "Ref Des/Assembly Top")
		(33 "B.Fab" user "Ref Des/Assembly Bottom")
	)
	(footprint ""
		(layer "F.Cu")
		(at 6.799326 -293.878254)
		(property "Reference" "Q251"
			(at 0 0 0)
			(layer "F.SilkS")
			(hide yes)
			(effects
				(font
					(size 1.27 1.27)
				)
			)
		)
		(property "Value" "2N7002K-2-GP"
			(at 0.127 -8.9662 0)
			(unlocked yes)
			(layer "F.Fab")
			(hide yes)
			(effects
				(font
					(size 1.016 1.016)
					(thickness 0.1524)
				)
			)
		)
		(property "Device Type" "SOT23DGS2D4H44"
			(at 0.127 -10.4902 0)
			(unlocked yes)
			(layer "F.Fab")
			(hide yes)
			(effects
				(font
					(size 1.016 1.016)
					(thickness 0.1524)
				)
			)
		)
		(duplicate_pad_numbers_are_jumpers no)
		(fp_line
			(start -1.651 -1.778)
			(end -1.651 1.778)
			(stroke
				(width 0.1524)
				(type default)
			)
			(layer "F.SilkS")
		)
		(fp_line
			(start -1.651 1.778)
			(end 1.651 1.778)
			(stroke
				(width 0.1524)
				(type default)
			)
			(layer "F.SilkS")
		)
		(fp_line
			(start 1.651 -1.778)
			(end -1.651 -1.778)
			(stroke
				(width 0.1524)
				(type default)
			)
			(layer "F.SilkS")
		)
		(fp_line
			(start 1.651 1.778)
			(end 1.651 -1.778)
			(stroke
				(width 0.1524)
				(type default)
			)
			(layer "F.SilkS")
		)
		(fp_poly
			(pts
				(xy -1.778 1.8796) (xy -1.778 -1.8796) (xy 1.778 -1.8796) (xy 1.778 1.8796)
			)
			(stroke
				(width 0)
				(type default)
			)
			(fill no)
			(layer "F.CrtYd")
		)
		(fp_poly
			(pts
				(xy -1.778 1.8796) (xy -1.778 -1.8796) (xy 1.778 -1.8796) (xy 1.778 1.8796)
			)
			(stroke
				(width 0)
				(type default)
			)
			(fill no)
			(layer "F.Fab")
		)
		(pad "D" smd custom
			(at 0 -0.9525)
			(size 0.1905 0.1905)
			(layers "F.Cu" "F.Mask" "F.Paste")
			(net "FLT_HDD24_N")
			(options
				(clearance outline)
				(anchor circle)
			)
			(primitives
				(gr_poly
					(pts
						(arc
							(start -0.1778 0.5715)
							(mid -0.321484 0.511984)
							(end -0.381 0.3683)
						)
						(arc
							(start -0.381 -0.3683)
							(mid -0.321484 -0.511984)
							(end -0.1778 -0.5715)
						)
						(arc
							(start 0.1778 -0.5715)
							(mid 0.321484 -0.511984)
							(end 0.381 -0.3683)
						)
						(arc
							(start 0.381 0.3683)
							(mid 0.321484 0.511984)
							(end 0.1778 0.5715)
						)
					)
					(width 0)
					(fill yes)
				)
			)
		)
		(pad "G" smd custom
			(at -0.98425 0.9525)
			(size 0.1905 0.1905)
			(layers "F.Cu" "F.Mask" "F.Paste")
			(net "DRIVE_B_24_FLT_LED")
			(options
				(clearance outline)
				(anchor circle)
			)
			(primitives
				(gr_poly
					(pts
						(arc
							(start -0.1778 0.5715)
							(mid -0.321484 0.511984)
							(end -0.381 0.3683)
						)
						(arc
							(start -0.381 -0.3683)
							(mid -0.321484 -0.511984)
							(end -0.1778 -0.5715)
						)
						(arc
							(start 0.1778 -0.5715)
							(mid 0.321484 -0.511984)
							(end 0.381 -0.3683)
						)
						(arc
							(start 0.381 0.3683)
							(mid 0.321484 0.511984)
							(end 0.1778 0.5715)
						)
					)
					(width 0)
					(fill yes)
				)
			)
		)
		(pad "S" smd custom
			(at 0.98425 0.9525)
			(size 0.1905 0.1905)
			(layers "F.Cu" "F.Mask" "F.Paste")
			(net "GND")
			(options
				(clearance outline)
				(anchor circle)
			)
			(primitives
				(gr_poly
					(pts
						(arc
							(start -0.1778 0.5715)
							(mid -0.321484 0.511984)
							(end -0.381 0.3683)
						)
						(arc
							(start -0.381 -0.3683)
							(mid -0.321484 -0.511984)
							(end -0.1778 -0.5715)
						)
						(arc
							(start 0.1778 -0.5715)
							(mid 0.321484 -0.511984)
							(end 0.381 -0.3683)
						)
						(arc
							(start 0.381 0.3683)
							(mid 0.321484 0.511984)
							(end 0.1778 0.5715)
						)
					)
					(width 0)
					(fill yes)
				)
			)
		)
	)
	(footprint ""
		(layer "F.Cu")
		(at 376.9614 -142.3416 90)
		(property "Reference" "R1076"
			(at 0 0 90)
			(layer "F.SilkS")
			(hide yes)
			(effects
				(font
					(size 1.27 1.27)
				)
			)
		)
		(property "Value" "0R2J-2-GP"
			(at 0.064008 -3.993896 90)
			(unlocked yes)
			(layer "F.Fab")
			(hide yes)
			(effects
				(font
					(size 1.016 1.016)
					(thickness 0.1524)
				)
			)
		)
		(property "Device Type" "R402H16"
			(at 0.064008 -5.517896 90)
			(unlocked yes)
			(layer "F.Fab")
			(hide yes)
			(effects
				(font
					(size 1.016 1.016)
					(thickness 0.1524)
				)
			)
		)
		(duplicate_pad_numbers_are_jumpers no)
		(fp_line
			(start 0.508 -0.9398)
			(end -0.508 -0.9398)
			(stroke
				(width 0.1524)
				(type default)
			)
			(layer "F.SilkS")
		)
		(fp_line
			(start -0.508 -0.9398)
			(end -0.508 0.9398)
			(stroke
				(width 0.1524)
				(type default)
			)
			(layer "F.SilkS")
		)
		(fp_rect
			(start -0.508 0.9398)
			(end 0.508 -0.9398)
			(stroke
				(width 0)
				(type default)
			)
			(fill no)
			(layer "F.CrtYd")
		)
		(fp_rect
			(start -0.508 0.9398)
			(end 0.508 -0.9398)
			(stroke
				(width 0)
				(type default)
			)
			(fill no)
			(layer "F.Fab")
		)
		(pad "1" smd custom
			(at 0 -0.4445 90)
			(size 0.1397 0.1397)
			(layers "F.Cu" "F.Mask" "F.Paste")
			(net "MB1_SCL_R")
			(options
				(clearance outline)
				(anchor circle)
			)
			(primitives
				(gr_poly
					(pts
						(arc
							(start -0.1778 -0.2794)
							(mid -0.249642 -0.249642)
							(end -0.2794 -0.1778)
						)
						(arc
							(start -0.2794 0.1778)
							(mid -0.249642 0.249642)
							(end -0.1778 0.2794)
						)
						(arc
							(start 0.1778 0.2794)
							(mid 0.249642 0.249642)
							(end 0.2794 0.1778)
						)
						(arc
							(start 0.2794 -0.1778)
							(mid 0.249642 -0.249642)
							(end 0.1778 -0.2794)
						)
					)
					(width 0)
					(fill yes)
				)
			)
		)
		(pad "2" smd custom
			(at 0 0.4445 90)
			(size 0.1397 0.1397)
			(layers "F.Cu" "F.Mask" "F.Paste")
			(net "I2C_BMC_B_MISC_SCL")
			(options
				(clearance outline)
				(anchor circle)
			)
			(primitives
				(gr_poly
					(pts
						(arc
							(start -0.1778 -0.2794)
							(mid -0.249642 -0.249642)
							(end -0.2794 -0.1778)
						)
						(arc
							(start -0.2794 0.1778)
							(mid -0.249642 0.249642)
							(end -0.1778 0.2794)
						)
						(arc
							(start 0.1778 0.2794)
							(mid 0.249642 0.249642)
							(end 0.2794 0.1778)
						)
						(arc
							(start 0.2794 -0.1778)
							(mid 0.249642 -0.249642)
							(end 0.1778 -0.2794)
						)
					)
					(width 0)
					(fill yes)
				)
			)
		)
	)
	(footprint ""
		(layer "F.Cu")
		(at 116.739162 -159.939228 90)
		(property "Reference" "R485"
			(at 0 0 90)
			(layer "F.SilkS")
			(hide yes)
			(effects
				(font
					(size 1.27 1.27)
				)
			)
		)
		(property "Value" "0R2J-2-GP"
			(at 0.064008 -3.993896 90)
			(unlocked yes)
			(layer "F.Fab")
			(hide yes)
			(effects
				(font
					(size 1.016 1.016)
					(thickness 0.1524)
				)
			)
		)
		(property "Device Type" "R402H16"
			(at 0.064008 -5.517896 90)
			(unlocked yes)
			(layer "F.Fab")
			(hide yes)
			(effects
				(font
					(size 1.016 1.016)
					(thickness 0.1524)
				)
			)
		)
		(duplicate_pad_numbers_are_jumpers no)
		(fp_line
			(start 0.508 -0.9398)
			(end -0.508 -0.9398)
			(stroke
				(width 0.1524)
				(type default)
			)
			(layer "F.SilkS")
		)
		(fp_line
			(start -0.508 -0.9398)
			(end -0.508 0.9398)
			(stroke
				(width 0.1524)
				(type default)
			)
			(layer "F.SilkS")
		)
		(fp_rect
			(start -0.508 0.9398)
			(end 0.508 -0.9398)
			(stroke
				(width 0)
				(type default)
			)
			(fill no)
			(layer "F.CrtYd")
		)
		(fp_rect
			(start -0.508 0.9398)
			(end 0.508 -0.9398)
			(stroke
				(width 0)
				(type default)
			)
			(fill no)
			(layer "F.Fab")
		)
		(pad "1" smd custom
			(at 0 -0.4445 90)
			(size 0.1397 0.1397)
			(layers "F.Cu" "F.Mask" "F.Paste")
			(net "DRIVE_A_15_PWR")
			(options
				(clearance outline)
				(anchor circle)
			)
			(primitives
				(gr_poly
					(pts
						(arc
							(start -0.1778 -0.2794)
							(mid -0.249642 -0.249642)
							(end -0.2794 -0.1778)
						)
						(arc
							(start -0.2794 0.1778)
							(mid -0.249642 0.249642)
							(end -0.1778 0.2794)
						)
						(arc
							(start 0.1778 0.2794)
							(mid 0.249642 0.249642)
							(end 0.2794 0.1778)
						)
						(arc
							(start 0.2794 -0.1778)
							(mid 0.249642 -0.249642)
							(end 0.1778 -0.2794)
						)
					)
					(width 0)
					(fill yes)
				)
			)
		)
		(pad "2" smd custom
			(at 0 0.4445 90)
			(size 0.1397 0.1397)
			(layers "F.Cu" "F.Mask" "F.Paste")
			(net "SW_PWR_R_HDD15")
			(options
				(clearance outline)
				(anchor circle)
			)
			(primitives
				(gr_poly
					(pts
						(arc
							(start -0.1778 -0.2794)
							(mid -0.249642 -0.249642)
							(end -0.2794 -0.1778)
						)
						(arc
							(start -0.2794 0.1778)
							(mid -0.249642 0.249642)
							(end -0.1778 0.2794)
						)
						(arc
							(start 0.1778 0.2794)
							(mid 0.249642 0.249642)
							(end 0.2794 0.1778)
						)
						(arc
							(start 0.2794 -0.1778)
							(mid 0.249642 -0.249642)
							(end 0.1778 -0.2794)
						)
					)
					(width 0)
					(fill yes)
				)
			)
		)
	)
	(footprint ""
		(layer "F.Cu")
		(at 81.51495 -127.254)
		(property "Reference" "R292"
			(at 0 0 0)
			(layer "F.SilkS")
			(hide yes)
			(effects
				(font
					(size 1.27 1.27)
				)
			)
		)
		(property "Value" "91R3F-1-GP"
			(at -0.0254 -2.5146 0)
			(unlocked yes)
			(layer "F.Fab")
			(hide yes)
			(effects
				(font
					(size 1.016 1.016)
					(thickness 0.1524)
				)
			)
		)
		(property "Device Type" "R603H22"
			(at -0.0254 -4.0386 0)
			(unlocked yes)
			(layer "F.Fab")
			(hide yes)
			(effects
				(font
					(size 1.016 1.016)
					(thickness 0.1524)
				)
			)
		)
		(duplicate_pad_numbers_are_jumpers no)
		(fp_line
			(start -0.4826 0)
			(end -0.2032 0)
			(stroke
				(width 0.2032)
				(type default)
			)
			(layer "F.SilkS")
		)
		(fp_line
			(start 0.2032 0)
			(end 0.4826 0)
			(stroke
				(width 0.2032)
				(type default)
			)
			(layer "F.SilkS")
		)
		(fp_rect
			(start -0.5842 1.3335)
			(end 0.5842 -1.3335)
			(stroke
				(width 0)
				(type default)
			)
			(fill no)
			(layer "F.CrtYd")
		)
		(fp_rect
			(start -0.5842 1.3335)
			(end 0.5842 -1.3335)
			(stroke
				(width 0)
				(type default)
			)
			(fill no)
			(layer "F.Fab")
		)
		(pad "1" smd custom
			(at 0 -0.762)
			(size 0.2159 0.2159)
			(layers "F.Cu" "F.Mask" "F.Paste")
			(net "P5V_A_1")
			(options
				(clearance outline)
				(anchor circle)
			)
			(primitives
				(gr_poly
					(pts
						(arc
							(start -0.3302 -0.4318)
							(mid -0.402042 -0.402042)
							(end -0.4318 -0.3302)
						)
						(arc
							(start -0.4318 0.3302)
							(mid -0.402042 0.402042)
							(end -0.3302 0.4318)
						)
						(arc
							(start 0.3302 0.4318)
							(mid 0.402042 0.402042)
							(end 0.4318 0.3302)
						)
						(arc
							(start 0.4318 -0.3302)
							(mid 0.402042 -0.402042)
							(end 0.3302 -0.4318)
						)
					)
					(width 0)
					(fill yes)
				)
			)
		)
		(pad "2" smd custom
			(at 0 0.762)
			(size 0.2159 0.2159)
			(layers "F.Cu" "F.Mask" "F.Paste")
			(net "DRV_ACT_14")
			(options
				(clearance outline)
				(anchor circle)
			)
			(primitives
				(gr_poly
					(pts
						(arc
							(start -0.3302 -0.4318)
							(mid -0.402042 -0.402042)
							(end -0.4318 -0.3302)
						)
						(arc
							(start -0.4318 0.3302)
							(mid -0.402042 0.402042)
							(end -0.3302 0.4318)
						)
						(arc
							(start 0.3302 0.4318)
							(mid 0.402042 0.402042)
							(end 0.4318 0.3302)
						)
						(arc
							(start 0.4318 -0.3302)
							(mid 0.402042 -0.402042)
							(end 0.3302 -0.4318)
						)
					)
					(width 0)
					(fill yes)
				)
			)
		)
	)
)
